# S9S_MB_2U (Grand Teton) — schematic netlist excerpt (pin names and nets, part order shuffled) for the footprints in the layout excerpt that follows; sources: Cadence DE-HDL packaged netlist, KiCad conversion of 03242023_DA0F0TMBIJ0_F0T_Motherboard_J_brd_V01_OCP.brd

R1409  Q_RES  2K 1% CHIP  pkg 0402LF  page 219 : A = FM_PVCCFA_EHV_CPU0_R_EN ; B = GND
PR3991  Q_RES  2K 0.1% CHIP  pkg 0402LF  page 303 : A = HSC_IMON ; B = AGND_HSC

(kicad_pcb
	(version 20260206)
	(generator "pcbnew")
	(generator_version "10.0")
	(general
		(thickness 1.6)
		(legacy_teardrops no)
	)
	(paper "A4")
	(title_block
		(title "03242023_DA0F0TMBIJ0_F0T_Motherboard_J_brd_V01_OCP.brd")
		(comment 1 "Grand Teton / footprints 3121-3122 of 6105")
	)
	(layers
		(0 "F.Cu" signal "TOP")
		(4 "In1.Cu" signal "GND")
		(6 "In2.Cu" signal "IN1")
		(8 "In3.Cu" signal "GND1")
		(10 "In4.Cu" signal "IN2")
		(12 "In5.Cu" signal "GND2")
		(14 "In6.Cu" signal "IN3")
		(16 "In7.Cu" signal "GND3")
		(18 "In8.Cu" signal "VCC")
		(20 "In9.Cu" signal "VCC1")
		(22 "In10.Cu" signal "GND4")
		(24 "In11.Cu" signal "IN4")
		(26 "In12.Cu" signal "GND5")
		(28 "In13.Cu" signal "IN5")
		(30 "In14.Cu" signal "GND6")
		(32 "In15.Cu" signal "IN6")
		(34 "In16.Cu" signal "GND7")
		(2 "B.Cu" signal "BOTTOM")
		(9 "F.Adhes" user "F.Adhesive")
		(11 "B.Adhes" user "B.Adhesive")
		(13 "F.Paste" user "Package Geometry/Pastemask Top")
		(15 "B.Paste" user "Package Geometry/Pastemask Bottom")
		(5 "F.SilkS" user "Ref Des/Silkscreen Top")
		(7 "B.SilkS" user "Ref Des/Silkscreen Bottom")
		(1 "F.Mask" user "Board Geometry/Soldermask Top")
		(3 "B.Mask" user "Board Geometry/Soldermask Bottom")
		(17 "Dwgs.User" user "User.Drawings")
		(19 "Cmts.User" user "User.Comments")
		(21 "Eco1.User" user "User.Eco1")
		(23 "Eco2.User" user "User.Eco2")
		(25 "Edge.Cuts" user "Board Geometry/Outline")
		(27 "Margin" user)
		(31 "F.CrtYd" user "Package Geometry/Place Bound Top")
		(29 "B.CrtYd" user "Package Geometry/Place Bound Bottom")
		(35 "F.Fab" user "Ref Des/Assembly Top")
		(33 "B.Fab" user "Ref Des/Assembly Bottom")
	)
	(footprint ""
		(layer "F.Cu")
		(at 160.83788 -118.836948 180)
		(property "Reference" "R1409"
			(at 0 0 180)
			(layer "F.SilkS")
			(hide yes)
			(effects
				(font
					(size 1.27 1.27)
				)
			)
		)
		(property "Value" ""
			(at 0 0 180)
			(layer "F.Fab")
			(effects
				(font
					(size 1.27 1.27)
				)
			)
		)
		(duplicate_pad_numbers_are_jumpers no)
		(fp_line
			(start 0.7874 0.4064)
			(end -0.7874 0.4064)
			(stroke
				(width 0.1524)
				(type default)
			)
			(layer "F.SilkS")
		)
		(fp_line
			(start 0.7874 -0.4064)
			(end 0.7874 0.4064)
			(stroke
				(width 0.1524)
				(type default)
			)
			(layer "F.SilkS")
		)
		(fp_line
			(start -0.7874 0.4064)
			(end -0.7874 -0.4064)
			(stroke
				(width 0.1524)
				(type default)
			)
			(layer "F.SilkS")
		)
		(fp_line
			(start -0.7874 -0.4064)
			(end 0.7874 -0.4064)
			(stroke
				(width 0.1524)
				(type default)
			)
			(layer "F.SilkS")
		)
		(fp_line
			(start 0.67945 0.3048)
			(end 0.120396 0.3048)
			(stroke
				(width 0.1)
				(type default)
			)
			(layer "F.Fab")
		)
		(fp_line
			(start 0.67945 -0.3048)
			(end 0.67945 0.3048)
			(stroke
				(width 0.1)
				(type default)
			)
			(layer "F.Fab")
		)
		(fp_line
			(start 0.12065 -0.2794)
			(end 0.12065 -0.3048)
			(stroke
				(width 0.1)
				(type default)
			)
			(layer "F.Fab")
		)
		(fp_line
			(start 0.12065 -0.3048)
			(end 0.67945 -0.3048)
			(stroke
				(width 0.1)
				(type default)
			)
			(layer "F.Fab")
		)
		(fp_line
			(start 0.120396 0.3048)
			(end 0.120396 0.2794)
			(stroke
				(width 0.1)
				(type default)
			)
			(layer "F.Fab")
		)
		(fp_line
			(start 0.120396 0.2794)
			(end -0.12065 0.2794)
			(stroke
				(width 0.1)
				(type default)
			)
			(layer "F.Fab")
		)
		(fp_line
			(start -0.12065 0.3048)
			(end -0.67945 0.3048)
			(stroke
				(width 0.1)
				(type default)
			)
			(layer "F.Fab")
		)
		(fp_line
			(start -0.12065 0.2794)
			(end -0.12065 0.3048)
			(stroke
				(width 0.1)
				(type default)
			)
			(layer "F.Fab")
		)
		(fp_line
			(start -0.12065 -0.2794)
			(end 0.12065 -0.2794)
			(stroke
				(width 0.1)
				(type default)
			)
			(layer "F.Fab")
		)
		(fp_line
			(start -0.12065 -0.305054)
			(end -0.12065 -0.2794)
			(stroke
				(width 0.1)
				(type default)
			)
			(layer "F.Fab")
		)
		(fp_line
			(start -0.67945 0.3048)
			(end -0.67945 -0.305054)
			(stroke
				(width 0.1)
				(type default)
			)
			(layer "F.Fab")
		)
		(fp_line
			(start -0.67945 -0.305054)
			(end -0.12065 -0.305054)
			(stroke
				(width 0.1)
				(type default)
			)
			(layer "F.Fab")
		)
		(pad "1" smd circle
			(at -0.40005 0 180)
			(size 0 0)
			(layers "F.Cu" "F.Mask" "F.Paste")
			(net "FM_PVCCFA_EHV_CPU0_R_EN")
		)
		(pad "2" smd circle
			(at 0.40005 0 180)
			(size 0 0)
			(layers "F.Cu" "F.Mask" "F.Paste")
			(net "GND")
		)
	)
	(footprint ""
		(layer "F.Cu")
		(at 226.733608 -402.791422 180)
		(property "Reference" "PR3991"
			(at 0 0 180)
			(layer "F.SilkS")
			(hide yes)
			(effects
				(font
					(size 1.27 1.27)
				)
			)
		)
		(property "Value" ""
			(at 0 0 180)
			(layer "F.Fab")
			(effects
				(font
					(size 1.27 1.27)
				)
			)
		)
		(duplicate_pad_numbers_are_jumpers no)
		(fp_line
			(start 0.7874 0.4064)
			(end -0.7874 0.4064)
			(stroke
				(width 0.1524)
				(type default)
			)
			(layer "F.SilkS")
		)
		(fp_line
			(start 0.7874 -0.4064)
			(end 0.7874 0.4064)
			(stroke
				(width 0.1524)
				(type default)
			)
			(layer "F.SilkS")
		)
		(fp_line
			(start -0.7874 0.4064)
			(end -0.7874 -0.4064)
			(stroke
				(width 0.1524)
				(type default)
			)
			(layer "F.SilkS")
		)
		(fp_line
			(start -0.7874 -0.4064)
			(end 0.7874 -0.4064)
			(stroke
				(width 0.1524)
				(type default)
			)
			(layer "F.SilkS")
		)
		(fp_line
			(start 0.67945 0.3048)
			(end 0.120396 0.3048)
			(stroke
				(width 0.1)
				(type default)
			)
			(layer "F.Fab")
		)
		(fp_line
			(start 0.67945 -0.3048)
			(end 0.67945 0.3048)
			(stroke
				(width 0.1)
				(type default)
			)
			(layer "F.Fab")
		)
		(fp_line
			(start 0.12065 -0.2794)
			(end 0.12065 -0.3048)
			(stroke
				(width 0.1)
				(type default)
			)
			(layer "F.Fab")
		)
		(fp_line
			(start 0.12065 -0.3048)
			(end 0.67945 -0.3048)
			(stroke
				(width 0.1)
				(type default)
			)
			(layer "F.Fab")
		)
		(fp_line
			(start 0.120396 0.3048)
			(end 0.120396 0.2794)
			(stroke
				(width 0.1)
				(type default)
			)
			(layer "F.Fab")
		)
		(fp_line
			(start 0.120396 0.2794)
			(end -0.12065 0.2794)
			(stroke
				(width 0.1)
				(type default)
			)
			(layer "F.Fab")
		)
		(fp_line
			(start -0.12065 0.3048)
			(end -0.67945 0.3048)
			(stroke
				(width 0.1)
				(type default)
			)
			(layer "F.Fab")
		)
		(fp_line
			(start -0.12065 0.2794)
			(end -0.12065 0.3048)
			(stroke
				(width 0.1)
				(type default)
			)
			(layer "F.Fab")
		)
		(fp_line
			(start -0.12065 -0.2794)
			(end 0.12065 -0.2794)
			(stroke
				(width 0.1)
				(type default)
			)
			(layer "F.Fab")
		)
		(fp_line
			(start -0.12065 -0.305054)
			(end -0.12065 -0.2794)
			(stroke
				(width 0.1)
				(type default)
			)
			(layer "F.Fab")
		)
		(fp_line
			(start -0.67945 0.3048)
			(end -0.67945 -0.305054)
			(stroke
				(width 0.1)
				(type default)
			)
			(layer "F.Fab")
		)
		(fp_line
			(start -0.67945 -0.305054)
			(end -0.12065 -0.305054)
			(stroke
				(width 0.1)
				(type default)
			)
			(layer "F.Fab")
		)
		(pad "1" smd circle
			(at -0.40005 0 180)
			(size 0 0)
			(layers "F.Cu" "F.Mask" "F.Paste")
			(net "HSC_IMON")
		)
		(pad "2" smd circle
			(at 0.40005 0 180)
			(size 0 0)
			(layers "F.Cu" "F.Mask" "F.Paste")
			(net "AGND_HSC")
		)
	)
)
